# T6G (Grand Teton) — schematic netlist excerpt (pin names and nets, part order shuffled) for the footprints in the layout excerpt that follows; sources: Cadence DE-HDL packaged netlist, KiCad conversion of 04192023_DAF0TMB3IC0_F0TG_MB_C_brd_V02_OCP.brd

R8114  Q_RES  17.8K 1% CHIP  pkg 0402LF  page 268 : A = P12V_AUX ; B = P12V_AUX_UV_ADR_TRIGGER
R2986  Q_RES  0 5% EMPTY  pkg 0402LF  page 248 : A = SMB_2_BMC_GPU_R_SCL ; B = SMB_2_BMC_GPU_BUF_R_SCL

(kicad_pcb
	(version 20260206)
	(generator "pcbnew")
	(generator_version "10.0")
	(general
		(thickness 1.6)
		(legacy_teardrops no)
	)
	(paper "A4")
	(title_block
		(title "04192023_DAF0TMB3IC0_F0TG_MB_C_brd_V02_OCP.brd")
		(comment 1 "Grand Teton / footprints 2342-2343 of 8354")
	)
	(layers
		(0 "F.Cu" signal "TOP")
		(4 "In1.Cu" signal "GND")
		(6 "In2.Cu" signal "IN1")
		(8 "In3.Cu" signal "GND1")
		(10 "In4.Cu" signal "IN2")
		(12 "In5.Cu" signal "GND2")
		(14 "In6.Cu" signal "IN3")
		(16 "In7.Cu" signal "GND3")
		(18 "In8.Cu" signal "VCC")
		(20 "In9.Cu" signal "VCC1")
		(22 "In10.Cu" signal "GND4")
		(24 "In11.Cu" signal "IN4")
		(26 "In12.Cu" signal "GND5")
		(28 "In13.Cu" signal "IN5")
		(30 "In14.Cu" signal "GND6")
		(32 "In15.Cu" signal "IN6")
		(34 "In16.Cu" signal "GND7")
		(2 "B.Cu" signal "BOTTOM")
		(9 "F.Adhes" user "F.Adhesive")
		(11 "B.Adhes" user "B.Adhesive")
		(13 "F.Paste" user "Package Geometry/Pastemask Top")
		(15 "B.Paste" user "Package Geometry/Pastemask Bottom")
		(5 "F.SilkS" user "Ref Des/Silkscreen Top")
		(7 "B.SilkS" user "Ref Des/Silkscreen Bottom")
		(1 "F.Mask" user "Board Geometry/Soldermask Top")
		(3 "B.Mask" user "Board Geometry/Soldermask Bottom")
		(17 "Dwgs.User" user "User.Drawings")
		(19 "Cmts.User" user "User.Comments")
		(21 "Eco1.User" user "User.Eco1")
		(23 "Eco2.User" user "User.Eco2")
		(25 "Edge.Cuts" user "Board Geometry/Outline")
		(27 "Margin" user)
		(31 "F.CrtYd" user "Package Geometry/Place Bound Top")
		(29 "B.CrtYd" user "Package Geometry/Place Bound Bottom")
		(35 "F.Fab" user "Ref Des/Assembly Top")
		(33 "B.Fab" user "Ref Des/Assembly Bottom")
	)
	(footprint ""
		(layer "F.Cu")
		(at 33.722818 -438.084214 -90)
		(property "Reference" "R2986"
			(at 0 0 270)
			(layer "F.SilkS")
			(hide yes)
			(effects
				(font
					(size 1.27 1.27)
				)
			)
		)
		(property "Value" ""
			(at 0 0 270)
			(layer "F.Fab")
			(effects
				(font
					(size 1.27 1.27)
				)
			)
		)
		(duplicate_pad_numbers_are_jumpers no)
		(fp_line
			(start -0.7874 0.4064)
			(end -0.7874 -0.4064)
			(stroke
				(width 0.1524)
				(type default)
			)
			(layer "F.SilkS")
		)
		(fp_line
			(start 0.7874 0.4064)
			(end -0.7874 0.4064)
			(stroke
				(width 0.1524)
				(type default)
			)
			(layer "F.SilkS")
		)
		(fp_line
			(start -0.7874 -0.4064)
			(end 0.7874 -0.4064)
			(stroke
				(width 0.1524)
				(type default)
			)
			(layer "F.SilkS")
		)
		(fp_line
			(start 0.7874 -0.4064)
			(end 0.7874 0.4064)
			(stroke
				(width 0.1524)
				(type default)
			)
			(layer "F.SilkS")
		)
		(fp_line
			(start -0.67945 0.3048)
			(end -0.67945 -0.305054)
			(stroke
				(width 0.1)
				(type default)
			)
			(layer "F.Fab")
		)
		(fp_line
			(start -0.12065 0.3048)
			(end -0.67945 0.3048)
			(stroke
				(width 0.1)
				(type default)
			)
			(layer "F.Fab")
		)
		(fp_line
			(start 0.120396 0.3048)
			(end 0.120396 0.2794)
			(stroke
				(width 0.1)
				(type default)
			)
			(layer "F.Fab")
		)
		(fp_line
			(start 0.67945 0.3048)
			(end 0.120396 0.3048)
			(stroke
				(width 0.1)
				(type default)
			)
			(layer "F.Fab")
		)
		(fp_line
			(start -0.12065 0.2794)
			(end -0.12065 0.3048)
			(stroke
				(width 0.1)
				(type default)
			)
			(layer "F.Fab")
		)
		(fp_line
			(start 0.120396 0.2794)
			(end -0.12065 0.2794)
			(stroke
				(width 0.1)
				(type default)
			)
			(layer "F.Fab")
		)
		(fp_line
			(start -0.12065 -0.2794)
			(end 0.12065 -0.2794)
			(stroke
				(width 0.1)
				(type default)
			)
			(layer "F.Fab")
		)
		(fp_line
			(start 0.12065 -0.2794)
			(end 0.12065 -0.3048)
			(stroke
				(width 0.1)
				(type default)
			)
			(layer "F.Fab")
		)
		(fp_line
			(start 0.12065 -0.3048)
			(end 0.67945 -0.3048)
			(stroke
				(width 0.1)
				(type default)
			)
			(layer "F.Fab")
		)
		(fp_line
			(start 0.67945 -0.3048)
			(end 0.67945 0.3048)
			(stroke
				(width 0.1)
				(type default)
			)
			(layer "F.Fab")
		)
		(fp_line
			(start -0.67945 -0.305054)
			(end -0.12065 -0.305054)
			(stroke
				(width 0.1)
				(type default)
			)
			(layer "F.Fab")
		)
		(fp_line
			(start -0.12065 -0.305054)
			(end -0.12065 -0.2794)
			(stroke
				(width 0.1)
				(type default)
			)
			(layer "F.Fab")
		)
		(pad "1" smd circle
			(at -0.40005 0 270)
			(size 0 0)
			(layers "F.Cu" "F.Mask" "F.Paste")
			(net "SMB_2_BMC_GPU_R_SCL")
		)
		(pad "2" smd circle
			(at 0.40005 0 270)
			(size 0 0)
			(layers "F.Cu" "F.Mask" "F.Paste")
			(net "SMB_2_BMC_GPU_BUF_R_SCL")
		)
	)
	(footprint ""
		(layer "F.Cu")
		(at 130.048 -109.474 90)
		(property "Reference" "R8114"
			(at 0 0 90)
			(layer "F.SilkS")
			(hide yes)
			(effects
				(font
					(size 1.27 1.27)
				)
			)
		)
		(property "Value" ""
			(at 0 0 90)
			(layer "F.Fab")
			(effects
				(font
					(size 1.27 1.27)
				)
			)
		)
		(duplicate_pad_numbers_are_jumpers no)
		(fp_line
			(start 0.7874 -0.4064)
			(end 0.7874 0.4064)
			(stroke
				(width 0.1524)
				(type default)
			)
			(layer "F.SilkS")
		)
		(fp_line
			(start -0.7874 -0.4064)
			(end 0.7874 -0.4064)
			(stroke
				(width 0.1524)
				(type default)
			)
			(layer "F.SilkS")
		)
		(fp_line
			(start 0.7874 0.4064)
			(end -0.7874 0.4064)
			(stroke
				(width 0.1524)
				(type default)
			)
			(layer "F.SilkS")
		)
		(fp_line
			(start -0.7874 0.4064)
			(end -0.7874 -0.4064)
			(stroke
				(width 0.1524)
				(type default)
			)
			(layer "F.SilkS")
		)
		(fp_line
			(start -0.12065 -0.305054)
			(end -0.12065 -0.2794)
			(stroke
				(width 0.1)
				(type default)
			)
			(layer "F.Fab")
		)
		(fp_line
			(start -0.67945 -0.305054)
			(end -0.12065 -0.305054)
			(stroke
				(width 0.1)
				(type default)
			)
			(layer "F.Fab")
		)
		(fp_line
			(start 0.67945 -0.3048)
			(end 0.67945 0.3048)
			(stroke
				(width 0.1)
				(type default)
			)
			(layer "F.Fab")
		)
		(fp_line
			(start 0.12065 -0.3048)
			(end 0.67945 -0.3048)
			(stroke
				(width 0.1)
				(type default)
			)
			(layer "F.Fab")
		)
		(fp_line
			(start 0.12065 -0.2794)
			(end 0.12065 -0.3048)
			(stroke
				(width 0.1)
				(type default)
			)
			(layer "F.Fab")
		)
		(fp_line
			(start -0.12065 -0.2794)
			(end 0.12065 -0.2794)
			(stroke
				(width 0.1)
				(type default)
			)
			(layer "F.Fab")
		)
		(fp_line
			(start 0.120396 0.2794)
			(end -0.12065 0.2794)
			(stroke
				(width 0.1)
				(type default)
			)
			(layer "F.Fab")
		)
		(fp_line
			(start -0.12065 0.2794)
			(end -0.12065 0.3048)
			(stroke
				(width 0.1)
				(type default)
			)
			(layer "F.Fab")
		)
		(fp_line
			(start 0.67945 0.3048)
			(end 0.120396 0.3048)
			(stroke
				(width 0.1)
				(type default)
			)
			(layer "F.Fab")
		)
		(fp_line
			(start 0.120396 0.3048)
			(end 0.120396 0.2794)
			(stroke
				(width 0.1)
				(type default)
			)
			(layer "F.Fab")
		)
		(fp_line
			(start -0.12065 0.3048)
			(end -0.67945 0.3048)
			(stroke
				(width 0.1)
				(type default)
			)
			(layer "F.Fab")
		)
		(fp_line
			(start -0.67945 0.3048)
			(end -0.67945 -0.305054)
			(stroke
				(width 0.1)
				(type default)
			)
			(layer "F.Fab")
		)
		(pad "1" smd circle
			(at -0.40005 0 90)
			(size 0 0)
			(layers "F.Cu" "F.Mask" "F.Paste")
			(net "P12V_AUX")
		)
		(pad "2" smd circle
			(at 0.40005 0 90)
			(size 0 0)
			(layers "F.Cu" "F.Mask" "F.Paste")
			(net "P12V_AUX_UV_ADR_TRIGGER")
		)
	)
)
